(kicad_pcb
	(version 20260206)
	(generator "pcbnew")
	(generator_version "10.0")
	(general
		(thickness 1.6)
		(legacy_teardrops no)
	)
	(paper "A4")
	(title_block
		(title "baseboard — 13948-1b.1110WZS1818.brd")
		(comment 1 "Honey Badger (Wiwynn) / footprints 713-719 of 2523")
	)
	(layers
		(0 "F.Cu" signal "TOP")
		(4 "In1.Cu" signal "L2GND")
		(6 "In2.Cu" signal "L3")
		(8 "In3.Cu" signal "L4VCC")
		(10 "In4.Cu" signal "L5VCC")
		(12 "In5.Cu" signal "L6")
		(14 "In6.Cu" signal "L7GND")
		(2 "B.Cu" signal "BOTTOM")
		(9 "F.Adhes" user "F.Adhesive")
		(11 "B.Adhes" user "B.Adhesive")
		(13 "F.Paste" user "Package Geometry/Pastemask Top")
		(15 "B.Paste" user "Package Geometry/Pastemask Bottom")
		(5 "F.SilkS" user "Ref Des/Silkscreen Top")
		(7 "B.SilkS" user "Ref Des/Silkscreen Bottom")
		(1 "F.Mask" user "Board Geometry/Soldermask Top")
		(3 "B.Mask" user "Board Geometry/Soldermask Bottom")
		(17 "Dwgs.User" user "User.Drawings")
		(19 "Cmts.User" user "User.Comments")
		(21 "Eco1.User" user "User.Eco1")
		(23 "Eco2.User" user "User.Eco2")
		(25 "Edge.Cuts" user "Board Geometry/Outline")
		(27 "Margin" user)
		(31 "F.CrtYd" user "Package Geometry/Place Bound Top")
		(29 "B.CrtYd" user "Package Geometry/Place Bound Bottom")
		(35 "F.Fab" user "Ref Des/Assembly Top")
		(33 "B.Fab" user "Ref Des/Assembly Bottom")
	)
	(footprint ""
		(layer "F.Cu")
		(at 255.778 -118.618 90)
		(property "Reference" "U46"
			(at 0 0 90)
			(layer "F.SilkS")
			(hide yes)
			(effects
				(font
					(size 1.27 1.27)
				)
			)
		)
		(property "Value" "SN74LVC1G08DCKR-GP"
			(at -2.3368 -8.6868 90)
			(unlocked yes)
			(layer "F.Fab")
			(hide yes)
			(effects
				(font
					(size 1.016 1.016)
					(thickness 0.1524)
				)
			)
		)
		(property "Device Type" "SC70-5H44"
			(at -2.3114 -10.414 90)
			(unlocked yes)
			(layer "F.Fab")
			(hide yes)
			(effects
				(font
					(size 1.016 1.016)
					(thickness 0.1524)
				)
			)
		)
		(duplicate_pad_numbers_are_jumpers no)
		(fp_line
			(start 1.3843 -1.8034)
			(end 1.3843 -1.1176)
			(stroke
				(width 0.3302)
				(type default)
			)
			(layer "F.SilkS")
		)
		(fp_line
			(start 0.6604 -1.8034)
			(end 1.3843 -1.8034)
			(stroke
				(width 0.3302)
				(type default)
			)
			(layer "F.SilkS")
		)
		(fp_line
			(start 1.27 -1.7018)
			(end 1.27 1.7018)
			(stroke
				(width 0.1524)
				(type default)
			)
			(layer "F.SilkS")
		)
		(fp_line
			(start -1.27 -1.7018)
			(end 1.27 -1.7018)
			(stroke
				(width 0.1524)
				(type default)
			)
			(layer "F.SilkS")
		)
		(fp_line
			(start 1.27 1.7018)
			(end -1.27 1.7018)
			(stroke
				(width 0.1524)
				(type default)
			)
			(layer "F.SilkS")
		)
		(fp_line
			(start -1.27 1.7018)
			(end -1.27 -1.7018)
			(stroke
				(width 0.1524)
				(type default)
			)
			(layer "F.SilkS")
		)
		(fp_rect
			(start -1.524 1.9558)
			(end 1.524 -1.9558)
			(stroke
				(width 0)
				(type default)
			)
			(fill no)
			(layer "F.CrtYd")
		)
		(fp_poly
			(pts
				(xy -1.524 -1.9558) (xy 1.524 -1.9558) (xy 1.524 1.9558) (xy -1.524 1.9558)
			)
			(stroke
				(width 0)
				(type default)
			)
			(fill no)
			(layer "F.Fab")
		)
		(pad "1" smd rect
			(at 0.65024 -0.8255 90)
			(size 0.4064 1.2192)
			(layers "F.Cu" "F.Mask" "F.Paste")
			(net "CPU_U192_PIN3_RX_R")
		)
		(pad "2" smd rect
			(at 0 -0.8255 90)
			(size 0.4064 1.2192)
			(layers "F.Cu" "F.Mask" "F.Paste")
			(net "CPU_U193_PIN3_RX_R")
		)
		(pad "3" smd rect
			(at -0.65024 -0.8255 90)
			(size 0.4064 1.2192)
			(layers "F.Cu" "F.Mask" "F.Paste")
			(net "GND")
		)
		(pad "4" smd rect
			(at -0.65024 0.8255 90)
			(size 0.4064 1.2192)
			(layers "F.Cu" "F.Mask" "F.Paste")
			(net "CPU_RXD_R")
		)
		(pad "5" smd rect
			(at 0.65024 0.8255 90)
			(size 0.4064 1.2192)
			(layers "F.Cu" "F.Mask" "F.Paste")
			(net "P3V3_STBY")
		)
	)
	(footprint ""
		(layer "F.Cu")
		(at 333.375 -217.3605)
		(property "Reference" "R184"
			(at 0 0 0)
			(layer "F.SilkS")
			(hide yes)
			(effects
				(font
					(size 1.27 1.27)
				)
			)
		)
		(property "Value" "0R2J-2-GP"
			(at 0.064008 -3.993896 0)
			(unlocked yes)
			(layer "F.Fab")
			(hide yes)
			(effects
				(font
					(size 1.016 1.016)
					(thickness 0.1524)
				)
			)
		)
		(property "Device Type" "R402H16"
			(at 0.064008 -5.517896 0)
			(unlocked yes)
			(layer "F.Fab")
			(hide yes)
			(effects
				(font
					(size 1.016 1.016)
					(thickness 0.1524)
				)
			)
		)
		(duplicate_pad_numbers_are_jumpers no)
		(fp_line
			(start -0.508 -0.9398)
			(end -0.508 0.9398)
			(stroke
				(width 0.1524)
				(type default)
			)
			(layer "F.SilkS")
		)
		(fp_line
			(start 0.508 -0.9398)
			(end -0.508 -0.9398)
			(stroke
				(width 0.1524)
				(type default)
			)
			(layer "F.SilkS")
		)
		(fp_rect
			(start -0.508 0.9398)
			(end 0.508 -0.9398)
			(stroke
				(width 0)
				(type default)
			)
			(fill no)
			(layer "F.CrtYd")
		)
		(fp_rect
			(start -0.508 0.9398)
			(end 0.508 -0.9398)
			(stroke
				(width 0)
				(type default)
			)
			(fill no)
			(layer "F.Fab")
		)
		(pad "1" smd custom
			(at 0 -0.4445)
			(size 0.1397 0.1397)
			(layers "F.Cu" "F.Mask" "F.Paste")
			(net "VOL_SEN_SDA")
			(options
				(clearance outline)
				(anchor circle)
			)
			(primitives
				(gr_poly
					(pts
						(arc
							(start -0.1778 -0.2794)
							(mid -0.249642 -0.249642)
							(end -0.2794 -0.1778)
						)
						(arc
							(start -0.2794 0.1778)
							(mid -0.249642 0.249642)
							(end -0.1778 0.2794)
						)
						(arc
							(start 0.1778 0.2794)
							(mid 0.249642 0.249642)
							(end 0.2794 0.1778)
						)
						(arc
							(start 0.2794 -0.1778)
							(mid 0.249642 -0.249642)
							(end 0.1778 -0.2794)
						)
					)
					(width 0)
					(fill yes)
				)
			)
		)
		(pad "2" smd custom
			(at 0 0.4445)
			(size 0.1397 0.1397)
			(layers "F.Cu" "F.Mask" "F.Paste")
			(net "BMC_I2C_A_SDA")
			(options
				(clearance outline)
				(anchor circle)
			)
			(primitives
				(gr_poly
					(pts
						(arc
							(start -0.1778 -0.2794)
							(mid -0.249642 -0.249642)
							(end -0.2794 -0.1778)
						)
						(arc
							(start -0.2794 0.1778)
							(mid -0.249642 0.249642)
							(end -0.1778 0.2794)
						)
						(arc
							(start 0.1778 0.2794)
							(mid 0.249642 0.249642)
							(end 0.2794 0.1778)
						)
						(arc
							(start 0.2794 -0.1778)
							(mid 0.249642 -0.249642)
							(end 0.1778 -0.2794)
						)
					)
					(width 0)
					(fill yes)
				)
			)
		)
	)
	(footprint ""
		(layer "F.Cu")
		(at 315.4934 -209.1944)
		(property "Reference" "C90"
			(at 0 0 0)
			(layer "F.SilkS")
			(hide yes)
			(effects
				(font
					(size 1.27 1.27)
				)
			)
		)
		(property "Value" "SCD1U16V2KX-3GP"
			(at 1.1811 -2.7051 0)
			(unlocked yes)
			(layer "F.Fab")
			(hide yes)
			(effects
				(font
					(size 1.016 1.016)
					(thickness 0.1524)
				)
			)
		)
		(property "Device Type" "C402H22"
			(at 1.1811 -4.2291 0)
			(unlocked yes)
			(layer "F.Fab")
			(hide yes)
			(effects
				(font
					(size 1.016 1.016)
					(thickness 0.1524)
				)
			)
		)
		(duplicate_pad_numbers_are_jumpers no)
		(fp_rect
			(start -0.4318 0.9525)
			(end 0.4318 -0.9525)
			(stroke
				(width 0)
				(type default)
			)
			(fill no)
			(layer "F.CrtYd")
		)
		(fp_rect
			(start -0.4318 0.9525)
			(end 0.4318 -0.9525)
			(stroke
				(width 0)
				(type default)
			)
			(fill no)
			(layer "F.Fab")
		)
		(pad "1" smd custom
			(at 0 -0.4445)
			(size 0.1524 0.1524)
			(layers "F.Cu" "F.Mask" "F.Paste")
			(net "P1V8_STBY")
			(options
				(clearance outline)
				(anchor circle)
			)
			(primitives
				(gr_poly
					(pts
						(arc
							(start 0.3048 -0.2032)
							(mid 0.275042 -0.275042)
							(end 0.2032 -0.3048)
						)
						(arc
							(start -0.2032 -0.3048)
							(mid -0.275042 -0.275042)
							(end -0.3048 -0.2032)
						)
						(arc
							(start -0.3048 0.2032)
							(mid -0.275042 0.275042)
							(end -0.2032 0.3048)
						)
						(arc
							(start 0.2032 0.3048)
							(mid 0.275042 0.275042)
							(end 0.3048 0.2032)
						)
					)
					(width 0)
					(fill yes)
				)
			)
		)
		(pad "2" smd custom
			(at 0 0.4445)
			(size 0.1524 0.1524)
			(layers "F.Cu" "F.Mask" "F.Paste")
			(net "GND")
			(options
				(clearance outline)
				(anchor circle)
			)
			(primitives
				(gr_poly
					(pts
						(arc
							(start 0.3048 -0.2032)
							(mid 0.275042 -0.275042)
							(end 0.2032 -0.3048)
						)
						(arc
							(start -0.2032 -0.3048)
							(mid -0.275042 -0.275042)
							(end -0.3048 -0.2032)
						)
						(arc
							(start -0.3048 0.2032)
							(mid -0.275042 0.275042)
							(end -0.2032 0.3048)
						)
						(arc
							(start 0.2032 0.3048)
							(mid 0.275042 0.275042)
							(end 0.3048 0.2032)
						)
					)
					(width 0)
					(fill yes)
				)
			)
		)
	)
	(footprint ""
		(layer "F.Cu")
		(at 291.837872 -59.889136 180)
		(property "Reference" "PQ1"
			(at 0 0 180)
			(layer "F.SilkS")
			(hide yes)
			(effects
				(font
					(size 1.27 1.27)
				)
			)
		)
		(property "Value" "AO4406AL-GP"
			(at -3.707384 -1.5367 180)
			(unlocked yes)
			(layer "F.Fab")
			(hide yes)
			(effects
				(font
					(size 1.016 1.016)
					(thickness 0.1524)
				)
			)
		)
		(property "Device Type" "SOIC8H69"
			(at -3.707384 -3.0607 180)
			(unlocked yes)
			(layer "F.Fab")
			(hide yes)
			(effects
				(font
					(size 1.016 1.016)
					(thickness 0.1524)
				)
			)
		)
		(duplicate_pad_numbers_are_jumpers no)
		(fp_line
			(start 2.1336 1.4224)
			(end 2.1336 -1.4224)
			(stroke
				(width 0.1524)
				(type default)
			)
			(layer "F.SilkS")
		)
		(fp_line
			(start 2.1336 -1.4224)
			(end -2.7432 -1.4224)
			(stroke
				(width 0.1524)
				(type default)
			)
			(layer "F.SilkS")
		)
		(fp_line
			(start -2.1844 -0.0508)
			(end -2.7178 0.508)
			(stroke
				(width 0.1524)
				(type default)
			)
			(layer "F.SilkS")
		)
		(fp_line
			(start -2.6289 3.4417)
			(end -2.6289 1.4732)
			(stroke
				(width 0.381)
				(type default)
			)
			(layer "F.SilkS")
		)
		(fp_line
			(start -2.7178 -0.508)
			(end -2.1844 -0.0508)
			(stroke
				(width 0.1524)
				(type default)
			)
			(layer "F.SilkS")
		)
		(fp_line
			(start -2.7432 1.4224)
			(end 2.1336 1.4224)
			(stroke
				(width 0.1524)
				(type default)
			)
			(layer "F.SilkS")
		)
		(fp_line
			(start -2.7432 1.4224)
			(end -2.6416 1.4224)
			(stroke
				(width 0.1524)
				(type default)
			)
			(layer "F.SilkS")
		)
		(fp_line
			(start -2.7432 -1.4224)
			(end -2.7432 1.4224)
			(stroke
				(width 0.1524)
				(type default)
			)
			(layer "F.SilkS")
		)
		(fp_poly
			(pts
				(xy -2.2098 -1.4224) (xy -2.2098 1.4224) (xy 2.2098 1.4224) (xy 2.2098 -1.4224)
			)
			(stroke
				(width 0)
				(type default)
			)
			(fill yes)
			(layer "F.SilkS")
		)
		(fp_rect
			(start -2.450084 2.999994)
			(end 2.450084 -2.999994)
			(stroke
				(width 0)
				(type default)
			)
			(fill no)
			(layer "F.CrtYd")
		)
		(fp_poly
			(pts
				(xy -2.8194 3.6322) (xy -2.8194 -3.6322) (xy 2.8194 -3.6322) (xy 2.8194 1.18364) (xy 2.450084 1.18364)
				(xy 2.450084 -2.999994) (xy -2.450084 -2.999994) (xy -2.450084 2.999994) (xy 2.450084 2.999994)
				(xy 2.450084 1.18618) (xy 2.8194 1.18618) (xy 2.8194 3.6322)
			)
			(stroke
				(width 0)
				(type default)
			)
			(fill no)
			(layer "F.CrtYd")
		)
		(fp_rect
			(start -2.8194 3.6322)
			(end 2.8194 -3.6322)
			(stroke
				(width 0)
				(type default)
			)
			(fill no)
			(layer "F.Fab")
		)
		(pad "1" smd rect
			(at -1.905 2.54 180)
			(size 0.635 1.651)
			(layers "F.Cu" "F.Mask" "F.Paste")
			(net "P3V3")
		)
		(pad "2" smd rect
			(at -0.635 2.54 180)
			(size 0.635 1.651)
			(layers "F.Cu" "F.Mask" "F.Paste")
			(net "P3V3")
		)
		(pad "3" smd rect
			(at 0.635 2.54 180)
			(size 0.635 1.651)
			(layers "F.Cu" "F.Mask" "F.Paste")
			(net "P3V3")
		)
		(pad "4" smd rect
			(at 1.905 2.54 180)
			(size 0.635 1.651)
			(layers "F.Cu" "F.Mask" "F.Paste")
			(net "P3V3_EN_LV")
		)
		(pad "5" smd rect
			(at 1.905 -2.54 180)
			(size 0.635 1.651)
			(layers "F.Cu" "F.Mask" "F.Paste")
			(net "P3V3_STBY")
		)
		(pad "6" smd rect
			(at 0.635 -2.54 180)
			(size 0.635 1.651)
			(layers "F.Cu" "F.Mask" "F.Paste")
			(net "P3V3_STBY")
		)
		(pad "7" smd rect
			(at -0.635 -2.54 180)
			(size 0.635 1.651)
			(layers "F.Cu" "F.Mask" "F.Paste")
			(net "P3V3_STBY")
		)
		(pad "8" smd rect
			(at -1.905 -2.54 180)
			(size 0.635 1.651)
			(layers "F.Cu" "F.Mask" "F.Paste")
			(net "P3V3_STBY")
		)
	)
	(footprint ""
		(layer "F.Cu")
		(at 95.89897 -95.377 -90)
		(property "Reference" "SR782"
			(at 0 0 270)
			(layer "F.SilkS")
			(hide yes)
			(effects
				(font
					(size 1.27 1.27)
				)
			)
		)
		(property "Value" "4K7R2F-GP"
			(at 0.064008 -3.993896 270)
			(unlocked yes)
			(layer "F.Fab")
			(hide yes)
			(effects
				(font
					(size 1.016 1.016)
					(thickness 0.1524)
				)
			)
		)
		(property "Device Type" "R402H16"
			(at 0.064008 -5.517896 270)
			(unlocked yes)
			(layer "F.Fab")
			(hide yes)
			(effects
				(font
					(size 1.016 1.016)
					(thickness 0.1524)
				)
			)
		)
		(duplicate_pad_numbers_are_jumpers no)
		(fp_line
			(start -0.508 -0.9398)
			(end -0.508 0.9398)
			(stroke
				(width 0.1524)
				(type default)
			)
			(layer "F.SilkS")
		)
		(fp_line
			(start 0.508 -0.9398)
			(end -0.508 -0.9398)
			(stroke
				(width 0.1524)
				(type default)
			)
			(layer "F.SilkS")
		)
		(fp_rect
			(start -0.508 0.9398)
			(end 0.508 -0.9398)
			(stroke
				(width 0)
				(type default)
			)
			(fill no)
			(layer "F.CrtYd")
		)
		(fp_rect
			(start -0.508 0.9398)
			(end 0.508 -0.9398)
			(stroke
				(width 0)
				(type default)
			)
			(fill no)
			(layer "F.Fab")
		)
		(pad "1" smd custom
			(at 0 -0.4445 270)
			(size 0.1397 0.1397)
			(layers "F.Cu" "F.Mask" "F.Paste")
			(net "EXP_XM_ADDR_25")
			(options
				(clearance outline)
				(anchor circle)
			)
			(primitives
				(gr_poly
					(pts
						(arc
							(start -0.1778 -0.2794)
							(mid -0.249642 -0.249642)
							(end -0.2794 -0.1778)
						)
						(arc
							(start -0.2794 0.1778)
							(mid -0.249642 0.249642)
							(end -0.1778 0.2794)
						)
						(arc
							(start 0.1778 0.2794)
							(mid 0.249642 0.249642)
							(end 0.2794 0.1778)
						)
						(arc
							(start 0.2794 -0.1778)
							(mid 0.249642 -0.249642)
							(end 0.1778 -0.2794)
						)
					)
					(width 0)
					(fill yes)
				)
			)
		)
		(pad "2" smd custom
			(at 0 0.4445 270)
			(size 0.1397 0.1397)
			(layers "F.Cu" "F.Mask" "F.Paste")
			(net "GND")
			(options
				(clearance outline)
				(anchor circle)
			)
			(primitives
				(gr_poly
					(pts
						(arc
							(start -0.1778 -0.2794)
							(mid -0.249642 -0.249642)
							(end -0.2794 -0.1778)
						)
						(arc
							(start -0.2794 0.1778)
							(mid -0.249642 0.249642)
							(end -0.1778 0.2794)
						)
						(arc
							(start 0.1778 0.2794)
							(mid 0.249642 0.249642)
							(end 0.2794 0.1778)
						)
						(arc
							(start 0.2794 -0.1778)
							(mid 0.249642 -0.249642)
							(end 0.1778 -0.2794)
						)
					)
					(width 0)
					(fill yes)
				)
			)
		)
	)
	(footprint ""
		(layer "F.Cu")
		(at 324.739 -141.478 90)
		(property "Reference" "X2"
			(at 0 0 90)
			(layer "F.SilkS")
			(hide yes)
			(effects
				(font
					(size 1.27 1.27)
				)
			)
		)
		(property "Value" "X-32D768KHZ-56GP"
			(at 0 -5.0292 90)
			(unlocked yes)
			(layer "F.Fab")
			(hide yes)
			(effects
				(font
					(size 1.016 1.016)
					(thickness 0.1524)
				)
			)
		)
		(property "Device Type" "DST310SH34"
			(at 0 -6.5532 90)
			(unlocked yes)
			(layer "F.Fab")
			(hide yes)
			(effects
				(font
					(size 1.016 1.016)
					(thickness 0.1524)
				)
			)
		)
		(duplicate_pad_numbers_are_jumpers no)
		(fp_line
			(start 1.1303 -2.2479)
			(end 1.1303 2.2479)
			(stroke
				(width 0.1524)
				(type default)
			)
			(layer "F.SilkS")
		)
		(fp_line
			(start -1.1303 -2.2479)
			(end 1.1303 -2.2479)
			(stroke
				(width 0.1524)
				(type default)
			)
			(layer "F.SilkS")
		)
		(fp_line
			(start 1.1303 2.2479)
			(end -1.1303 2.2479)
			(stroke
				(width 0.1524)
				(type default)
			)
			(layer "F.SilkS")
		)
		(fp_line
			(start -1.1303 2.2479)
			(end -1.1303 -2.2479)
			(stroke
				(width 0.1524)
				(type default)
			)
			(layer "F.SilkS")
		)
		(fp_rect
			(start -1.3843 2.5019)
			(end 1.3843 -2.5019)
			(stroke
				(width 0)
				(type default)
			)
			(fill no)
			(layer "F.CrtYd")
		)
		(fp_rect
			(start -1.3843 2.5019)
			(end 1.3843 -2.5019)
			(stroke
				(width 0)
				(type default)
			)
			(fill no)
			(layer "F.Fab")
		)
		(pad "1" smd rect
			(at 0 -1.294384 90)
			(size 1.7526 1.397)
			(layers "F.Cu" "F.Mask" "F.Paste")
			(net "RTC_OSCI")
		)
		(pad "2" smd rect
			(at 0 1.294384 90)
			(size 1.7526 1.397)
			(layers "F.Cu" "F.Mask" "F.Paste")
			(net "RTC_OSCO")
		)
	)
	(footprint ""
		(layer "F.Cu")
		(at 265.675872 -44.903136 180)
		(property "Reference" "PC46"
			(at 0 0 180)
			(layer "F.SilkS")
			(hide yes)
			(effects
				(font
					(size 1.27 1.27)
				)
			)
		)
		(property "Value" "SC4D7U25V5KX-1-GP"
			(at -0.0762 -6.1214 180)
			(unlocked yes)
			(layer "F.Fab")
			(hide yes)
			(effects
				(font
					(size 1.016 1.016)
					(thickness 0.1524)
				)
			)
		)
		(property "Device Type" "C805H58"
			(at -0.0762 -8.1534 180)
			(unlocked yes)
			(layer "F.Fab")
			(hide yes)
			(effects
				(font
					(size 1.016 1.016)
					(thickness 0.1524)
				)
			)
		)
		(duplicate_pad_numbers_are_jumpers no)
		(fp_line
			(start 0.635 0)
			(end -0.635 0)
			(stroke
				(width 0.508)
				(type default)
			)
			(layer "F.SilkS")
		)
		(fp_rect
			(start -0.9652 1.778)
			(end 0.9652 -1.778)
			(stroke
				(width 0)
				(type default)
			)
			(fill no)
			(layer "F.CrtYd")
		)
		(fp_poly
			(pts
				(xy -0.9652 -1.778) (xy 0.9652 -1.778) (xy 0.9652 1.778) (xy -0.9652 1.778)
			)
			(stroke
				(width 0)
				(type default)
			)
			(fill no)
			(layer "F.Fab")
		)
		(pad "1" smd rect
			(at 0 -0.9652 180)
			(size 1.397 1.143)
			(layers "F.Cu" "F.Mask" "F.Paste")
			(net "P1V8_STBY_VDD")
		)
		(pad "2" smd rect
			(at 0 0.9652 180)
			(size 1.397 1.143)
			(layers "F.Cu" "F.Mask" "F.Paste")
			(net "GND")
		)
	)
)
